#ISCELL
  mstr_misc dns *
  *
#ISCELL
  mstr_symbols intel_corp_bpage *
  *
#ISCELL
  mstr_standard offpage *
  page208_i1
#ISCELL
  mstr_symbols gnd *
  page208_i10
#CELL
  mstr_discrete inductor *
  page208_i11
#CELL
  mstr_discrete capp *
  page208_i12
#ISCELL
  mstr_symbols gnd *
  page208_i13
#CELL
  mstr_discrete capp *
  page208_i14
#ISCELL
  mstr_standard offpage *
  page208_i16
#ISCELL
  mstr_standard offpage *
  page208_i17
#ISCELL
  mstr_symbols pvccin_cpu1 *
  page208_i18
#CELL
  mstr_discrete inductor *
  page208_i20
#ISCELL
  mstr_symbols gnd *
  page208_i21
#CELL
  dev_discrete cap_a *
  page208_i22
#ISCELL
  mstr_symbols gnd *
  page208_i23
#CELL
  mstr_discrete capp *
  page208_i24
#CELL
  mstr_discrete capp *
  page208_i25
#CELL
  mstr_discrete capp *
  page208_i26
#CELL
  mstr_discrete ir354xx *
  page208_i27
#CELL
  mstr_discrete capp *
  page208_i28
#ISCELL
  mstr_symbols pvccin_cpu1 *
  page208_i29
#ISCELL
  mstr_standard offpage *
  page208_i3
#CELL
  mstr_discrete capp *
  page208_i30
#ISCELL
  mstr_symbols gnd *
  page208_i33
#CELL
  mstr_discrete res *
  page208_i36
#ISCELL
  mstr_symbols vcc_core *
  page208_i37
#CELL
  mstr_discrete cap *
  page208_i38
#CELL
  dev_discrete cap_a *
  page208_i39
#CELL
  mstr_discrete cap *
  page208_i40
#CELL
  mstr_discrete cap *
  page208_i43
#CELL
  dev_discrete cap_a *
  page208_i44
#CELL
  mstr_discrete cap *
  page208_i45
#CELL
  mstr_discrete cap *
  page208_i46
#CELL
  dev_discrete cap_a *
  page208_i47
#CELL
  mstr_discrete cap *
  page208_i48
#CELL
  mstr_discrete res *
  page208_i49
#CELL
  mstr_discrete cap *
  page208_i50
#CELL
  dev_discrete cap_a *
  page208_i51
#CELL
  mstr_discrete cap *
  page208_i52
#CELL
  mstr_discrete cap *
  page208_i53
#CELL
  mstr_discrete cap *
  page208_i54
#CELL
  mstr_discrete cap *
  page208_i55
#ISCELL
  mstr_standard offpage *
  page208_i56
#ISCELL
  mstr_symbols gnd *
  page208_i57
#CELL
  mstr_discrete cap *
  page208_i58
#CELL
  mstr_discrete cap *
  page208_i59
#CELL
  mstr_discrete cap *
  page208_i60
#ISCELL
  mstr_standard offpage *
  page208_i61
#ISCELL
  mstr_symbols vcc_core *
  page208_i62
#ISCELL
  mstr_symbols gnd *
  page208_i63
#ISCELL
  mstr_symbols p5v_stby *
  page208_i64
#ISCELL
  mstr_symbols p5v_stby *
  page208_i65
#CELL
  dev_discrete cap_a *
  page208_i66
#CELL
  dev_discrete cap_a *
  page208_i67
#CELL
  mstr_discrete res *
  page208_i7
#ISCELL
  mstr_standard offpage *
  page208_i70
#CELL
  mstr_discrete ir354xx *
  page208_i71
#ISCELL
  mstr_standard offpage *
  page208_i72
#CELL
  mstr_discrete res *
  page208_i75
#CELL
  mstr_discrete res *
  page208_i76
#ISCELL
  mstr_symbols gnd *
  page208_i77
#ISCELL
  mstr_symbols gnd *
  page208_i78
#ISCELL
  mstr_symbols gnd *
  page208_i79
#ISCELL
  mstr_symbols pvccin_cpu1 *
  page208_i8
#CELL
  dev_discrete cap_a *
  page208_i80
#CELL
  mstr_discrete cap *
  page208_i82
#ISCELL
  mstr_symbols gnd *
  page208_i83
#CELL
  w_hdl sc2k2p50v3kx-gp *
  page208_i84
#ISCELL
  mstr_symbols gnd *
  page208_i85
#CELL
  w_hdl 3d01r5f-gp *
  page208_i86
#CELL
  dev_discrete cap_a *
  page208_i87
#ISCELL
  mstr_symbols gnd *
  page208_i88
#CELL
  dev_discrete cap_a *
  page208_i9
#CELL
  mstr_discrete cap *
  page208_i90
#ISCELL
  mstr_symbols gnd *
  page208_i91
#CELL
  w_hdl sc2k2p50v3kx-gp *
  page208_i92
#ISCELL
  mstr_symbols gnd *
  page208_i93
#CELL
  w_hdl 3d01r5f-gp *
  page208_i94
#CELL
  mstr_discrete res *
  page208_i96
#CELL
  mstr_discrete res *
  page208_i97
